(kicad_pcb
	(version 20260206)
	(generator "pcbnew")
	(generator_version "10.0")
	(general
		(thickness 1.6)
		(legacy_teardrops no)
	)
	(paper "A4")
	(title_block
		(title "04192023_DAF0TMB3IC0_F0TG_MB_C_brd_V02_OCP.brd")
		(comment 1 "Grand Teton / footprints 2478-2484 of 8354")
	)
	(layers
		(0 "F.Cu" signal "TOP")
		(4 "In1.Cu" signal "GND")
		(6 "In2.Cu" signal "IN1")
		(8 "In3.Cu" signal "GND1")
		(10 "In4.Cu" signal "IN2")
		(12 "In5.Cu" signal "GND2")
		(14 "In6.Cu" signal "IN3")
		(16 "In7.Cu" signal "GND3")
		(18 "In8.Cu" signal "VCC")
		(20 "In9.Cu" signal "VCC1")
		(22 "In10.Cu" signal "GND4")
		(24 "In11.Cu" signal "IN4")
		(26 "In12.Cu" signal "GND5")
		(28 "In13.Cu" signal "IN5")
		(30 "In14.Cu" signal "GND6")
		(32 "In15.Cu" signal "IN6")
		(34 "In16.Cu" signal "GND7")
		(2 "B.Cu" signal "BOTTOM")
		(9 "F.Adhes" user "F.Adhesive")
		(11 "B.Adhes" user "B.Adhesive")
		(13 "F.Paste" user "Package Geometry/Pastemask Top")
		(15 "B.Paste" user "Package Geometry/Pastemask Bottom")
		(5 "F.SilkS" user "Ref Des/Silkscreen Top")
		(7 "B.SilkS" user "Ref Des/Silkscreen Bottom")
		(1 "F.Mask" user "Board Geometry/Soldermask Top")
		(3 "B.Mask" user "Board Geometry/Soldermask Bottom")
		(17 "Dwgs.User" user "User.Drawings")
		(19 "Cmts.User" user "User.Comments")
		(21 "Eco1.User" user "User.Eco1")
		(23 "Eco2.User" user "User.Eco2")
		(25 "Edge.Cuts" user "Board Geometry/Outline")
		(27 "Margin" user)
		(31 "F.CrtYd" user "Package Geometry/Place Bound Top")
		(29 "B.CrtYd" user "Package Geometry/Place Bound Bottom")
		(35 "F.Fab" user "Ref Des/Assembly Top")
		(33 "B.Fab" user "Ref Des/Assembly Bottom")
	)
	(footprint ""
		(layer "F.Cu")
		(at 196.342 -137.632948 90)
		(property "Reference" "R1556"
			(at 0 0 90)
			(layer "F.SilkS")
			(hide yes)
			(effects
				(font
					(size 1.27 1.27)
				)
			)
		)
		(property "Value" ""
			(at 0 0 90)
			(layer "F.Fab")
			(effects
				(font
					(size 1.27 1.27)
				)
			)
		)
		(duplicate_pad_numbers_are_jumpers no)
		(fp_line
			(start 0.7874 -0.4064)
			(end 0.7874 0.4064)
			(stroke
				(width 0.1524)
				(type default)
			)
			(layer "F.SilkS")
		)
		(fp_line
			(start -0.7874 -0.4064)
			(end 0.7874 -0.4064)
			(stroke
				(width 0.1524)
				(type default)
			)
			(layer "F.SilkS")
		)
		(fp_line
			(start 0.7874 0.4064)
			(end -0.7874 0.4064)
			(stroke
				(width 0.1524)
				(type default)
			)
			(layer "F.SilkS")
		)
		(fp_line
			(start -0.7874 0.4064)
			(end -0.7874 -0.4064)
			(stroke
				(width 0.1524)
				(type default)
			)
			(layer "F.SilkS")
		)
		(fp_line
			(start -0.12065 -0.305054)
			(end -0.12065 -0.2794)
			(stroke
				(width 0.1)
				(type default)
			)
			(layer "F.Fab")
		)
		(fp_line
			(start -0.67945 -0.305054)
			(end -0.12065 -0.305054)
			(stroke
				(width 0.1)
				(type default)
			)
			(layer "F.Fab")
		)
		(fp_line
			(start 0.67945 -0.3048)
			(end 0.67945 0.3048)
			(stroke
				(width 0.1)
				(type default)
			)
			(layer "F.Fab")
		)
		(fp_line
			(start 0.12065 -0.3048)
			(end 0.67945 -0.3048)
			(stroke
				(width 0.1)
				(type default)
			)
			(layer "F.Fab")
		)
		(fp_line
			(start 0.12065 -0.2794)
			(end 0.12065 -0.3048)
			(stroke
				(width 0.1)
				(type default)
			)
			(layer "F.Fab")
		)
		(fp_line
			(start -0.12065 -0.2794)
			(end 0.12065 -0.2794)
			(stroke
				(width 0.1)
				(type default)
			)
			(layer "F.Fab")
		)
		(fp_line
			(start 0.120396 0.2794)
			(end -0.12065 0.2794)
			(stroke
				(width 0.1)
				(type default)
			)
			(layer "F.Fab")
		)
		(fp_line
			(start -0.12065 0.2794)
			(end -0.12065 0.3048)
			(stroke
				(width 0.1)
				(type default)
			)
			(layer "F.Fab")
		)
		(fp_line
			(start 0.67945 0.3048)
			(end 0.120396 0.3048)
			(stroke
				(width 0.1)
				(type default)
			)
			(layer "F.Fab")
		)
		(fp_line
			(start 0.120396 0.3048)
			(end 0.120396 0.2794)
			(stroke
				(width 0.1)
				(type default)
			)
			(layer "F.Fab")
		)
		(fp_line
			(start -0.12065 0.3048)
			(end -0.67945 0.3048)
			(stroke
				(width 0.1)
				(type default)
			)
			(layer "F.Fab")
		)
		(fp_line
			(start -0.67945 0.3048)
			(end -0.67945 -0.305054)
			(stroke
				(width 0.1)
				(type default)
			)
			(layer "F.Fab")
		)
		(pad "1" smd circle
			(at -0.40005 0 90)
			(size 0 0)
			(layers "F.Cu" "F.Mask" "F.Paste")
			(net "CLK_ESPI_CPU0_R1_CLK1")
		)
		(pad "2" smd circle
			(at 0.40005 0 90)
			(size 0 0)
			(layers "F.Cu" "F.Mask" "F.Paste")
			(net "CLK_ESPI_CPU0_CLK1")
		)
	)
	(footprint ""
		(layer "F.Cu")
		(at 435.102 -166.751 90)
		(property "Reference" "R1299"
			(at 0 0 90)
			(layer "F.SilkS")
			(hide yes)
			(effects
				(font
					(size 1.27 1.27)
				)
			)
		)
		(property "Value" ""
			(at 0 0 90)
			(layer "F.Fab")
			(effects
				(font
					(size 1.27 1.27)
				)
			)
		)
		(duplicate_pad_numbers_are_jumpers no)
		(fp_line
			(start 0.7874 -0.4064)
			(end 0.7874 0.4064)
			(stroke
				(width 0.1524)
				(type default)
			)
			(layer "F.SilkS")
		)
		(fp_line
			(start -0.7874 -0.4064)
			(end 0.7874 -0.4064)
			(stroke
				(width 0.1524)
				(type default)
			)
			(layer "F.SilkS")
		)
		(fp_line
			(start 0.7874 0.4064)
			(end -0.7874 0.4064)
			(stroke
				(width 0.1524)
				(type default)
			)
			(layer "F.SilkS")
		)
		(fp_line
			(start -0.7874 0.4064)
			(end -0.7874 -0.4064)
			(stroke
				(width 0.1524)
				(type default)
			)
			(layer "F.SilkS")
		)
		(fp_line
			(start -0.12065 -0.305054)
			(end -0.12065 -0.2794)
			(stroke
				(width 0.1)
				(type default)
			)
			(layer "F.Fab")
		)
		(fp_line
			(start -0.67945 -0.305054)
			(end -0.12065 -0.305054)
			(stroke
				(width 0.1)
				(type default)
			)
			(layer "F.Fab")
		)
		(fp_line
			(start 0.67945 -0.3048)
			(end 0.67945 0.3048)
			(stroke
				(width 0.1)
				(type default)
			)
			(layer "F.Fab")
		)
		(fp_line
			(start 0.12065 -0.3048)
			(end 0.67945 -0.3048)
			(stroke
				(width 0.1)
				(type default)
			)
			(layer "F.Fab")
		)
		(fp_line
			(start 0.12065 -0.2794)
			(end 0.12065 -0.3048)
			(stroke
				(width 0.1)
				(type default)
			)
			(layer "F.Fab")
		)
		(fp_line
			(start -0.12065 -0.2794)
			(end 0.12065 -0.2794)
			(stroke
				(width 0.1)
				(type default)
			)
			(layer "F.Fab")
		)
		(fp_line
			(start 0.120396 0.2794)
			(end -0.12065 0.2794)
			(stroke
				(width 0.1)
				(type default)
			)
			(layer "F.Fab")
		)
		(fp_line
			(start -0.12065 0.2794)
			(end -0.12065 0.3048)
			(stroke
				(width 0.1)
				(type default)
			)
			(layer "F.Fab")
		)
		(fp_line
			(start 0.67945 0.3048)
			(end 0.120396 0.3048)
			(stroke
				(width 0.1)
				(type default)
			)
			(layer "F.Fab")
		)
		(fp_line
			(start 0.120396 0.3048)
			(end 0.120396 0.2794)
			(stroke
				(width 0.1)
				(type default)
			)
			(layer "F.Fab")
		)
		(fp_line
			(start -0.12065 0.3048)
			(end -0.67945 0.3048)
			(stroke
				(width 0.1)
				(type default)
			)
			(layer "F.Fab")
		)
		(fp_line
			(start -0.67945 0.3048)
			(end -0.67945 -0.305054)
			(stroke
				(width 0.1)
				(type default)
			)
			(layer "F.Fab")
		)
		(pad "1" smd rect
			(at -0.40005 0 270)
			(size 0.4572 0.508)
			(layers "F.Cu" "F.Mask" "F.Paste")
			(net "I3C_SPD_DDRGL_CPU0_SCL")
		)
		(pad "2" smd rect
			(at 0.40005 0 270)
			(size 0.4572 0.508)
			(layers "F.Cu" "F.Mask" "F.Paste")
			(net "I3C_SPD_DDRGL_CPU0_LVC1_SCL")
		)
	)
	(footprint ""
		(layer "F.Cu")
		(at 93.113352 -72.61098 -90)
		(property "Reference" "PU207"
			(at -3.701542 2.497328 0)
			(unlocked yes)
			(layer "F.SilkS")
			(effects
				(font
					(size 0.7874 0.5842)
					(thickness 0.1524)
				)
			)
		)
		(property "Value" ""
			(at 0 0 270)
			(layer "F.Fab")
			(effects
				(font
					(size 1.27 1.27)
				)
			)
		)
		(duplicate_pad_numbers_are_jumpers no)
		(fp_line
			(start -1.239774 1.495298)
			(end -1.239774 -1.495298)
			(stroke
				(width 0.1524)
				(type default)
			)
			(layer "F.SilkS")
		)
		(fp_line
			(start 1.239774 1.495298)
			(end -1.239774 1.495298)
			(stroke
				(width 0.1524)
				(type default)
			)
			(layer "F.SilkS")
		)
		(fp_line
			(start -1.239774 -1.495298)
			(end 1.239774 -1.495298)
			(stroke
				(width 0.1524)
				(type default)
			)
			(layer "F.SilkS")
		)
		(fp_line
			(start 1.239774 -1.495298)
			(end 1.239774 1.495298)
			(stroke
				(width 0.1524)
				(type default)
			)
			(layer "F.SilkS")
		)
		(fp_poly
			(pts
				(xy -1.843532 -0.966724) (xy -2.921 -1.32588) (xy -2.202688 -2.044446)
			)
			(stroke
				(width 0)
				(type default)
			)
			(fill yes)
			(layer "F.SilkS")
		)
		(fp_line
			(start -0.8001 1.050036)
			(end -0.8001 -1.050036)
			(stroke
				(width 0.1)
				(type default)
			)
			(layer "F.Fab")
		)
		(fp_line
			(start 0.8001 1.050036)
			(end -0.8001 1.050036)
			(stroke
				(width 0.1)
				(type default)
			)
			(layer "F.Fab")
		)
		(fp_line
			(start -0.8001 -1.050036)
			(end 0.8001 -1.050036)
			(stroke
				(width 0.1)
				(type default)
			)
			(layer "F.Fab")
		)
		(fp_line
			(start 0.8001 -1.050036)
			(end 0.8001 1.050036)
			(stroke
				(width 0.1)
				(type default)
			)
			(layer "F.Fab")
		)
		(fp_poly
			(pts
				(xy -2.458974 -0.508) (xy -2.458974 0.508) (xy -1.442974 0)
			)
			(stroke
				(width 0)
				(type default)
			)
			(fill yes)
			(layer "F.Fab")
		)
		(pad "1_2" smd circle
			(at -0.374904 0)
			(size 0 0)
			(layers "F.Cu" "F.Mask" "F.Paste")
			(net "P3V3_AUX")
		)
		(pad "3" smd rect
			(at -0.499872 0.999998 270)
			(size 0.254 0.7112)
			(layers "F.Cu" "F.Mask" "F.Paste")
			(net "GND")
		)
		(pad "4" smd rect
			(at 0 0.999998 270)
			(size 0.254 0.7112)
			(layers "F.Cu" "F.Mask" "F.Paste")
			(net "P3V3_OCP_ILIMIT_2")
		)
		(pad "5" smd rect
			(at 0.499872 0.999998 270)
			(size 0.254 0.7112)
			(layers "F.Cu" "F.Mask" "F.Paste")
			(net "P3V3_OCP_MODE_2")
		)
		(pad "6_7" smd circle
			(at 0.374904 0 180)
			(size 0 0)
			(layers "F.Cu" "F.Mask" "F.Paste")
			(net "P3V3_OCP_V3_2_R")
		)
		(pad "8" smd rect
			(at 0.499872 -0.999998 270)
			(size 0.254 0.7112)
			(layers "F.Cu" "F.Mask" "F.Paste")
			(net "P3V3_OCP_GATE_PU207_2")
		)
		(pad "9" smd rect
			(at 0 -0.999998 270)
			(size 0.254 0.7112)
			(layers "F.Cu" "F.Mask" "F.Paste")
			(net "P3V3_OCP_EN_2")
		)
		(pad "10" smd rect
			(at -0.499872 -0.999998 270)
			(size 0.254 0.7112)
			(layers "F.Cu" "F.Mask" "F.Paste")
			(net "P3V3_OCP_DVDT_2")
		)
	)
	(footprint ""
		(layer "F.Cu")
		(at 254.592836 -125.52045)
		(property "Reference" "R3706"
			(at 0 0 0)
			(layer "F.SilkS")
			(hide yes)
			(effects
				(font
					(size 1.27 1.27)
				)
			)
		)
		(property "Value" ""
			(at 0 0 0)
			(layer "F.Fab")
			(effects
				(font
					(size 1.27 1.27)
				)
			)
		)
		(duplicate_pad_numbers_are_jumpers no)
		(fp_line
			(start -0.7874 -0.4064)
			(end 0.7874 -0.4064)
			(stroke
				(width 0.1524)
				(type default)
			)
			(layer "F.SilkS")
		)
		(fp_line
			(start -0.7874 0.4064)
			(end -0.7874 -0.4064)
			(stroke
				(width 0.1524)
				(type default)
			)
			(layer "F.SilkS")
		)
		(fp_line
			(start 0.7874 -0.4064)
			(end 0.7874 0.4064)
			(stroke
				(width 0.1524)
				(type default)
			)
			(layer "F.SilkS")
		)
		(fp_line
			(start 0.7874 0.4064)
			(end -0.7874 0.4064)
			(stroke
				(width 0.1524)
				(type default)
			)
			(layer "F.SilkS")
		)
		(fp_line
			(start -0.67945 -0.305054)
			(end -0.12065 -0.305054)
			(stroke
				(width 0.1)
				(type default)
			)
			(layer "F.Fab")
		)
		(fp_line
			(start -0.67945 0.3048)
			(end -0.67945 -0.305054)
			(stroke
				(width 0.1)
				(type default)
			)
			(layer "F.Fab")
		)
		(fp_line
			(start -0.12065 -0.305054)
			(end -0.12065 -0.2794)
			(stroke
				(width 0.1)
				(type default)
			)
			(layer "F.Fab")
		)
		(fp_line
			(start -0.12065 -0.2794)
			(end 0.12065 -0.2794)
			(stroke
				(width 0.1)
				(type default)
			)
			(layer "F.Fab")
		)
		(fp_line
			(start -0.12065 0.2794)
			(end -0.12065 0.3048)
			(stroke
				(width 0.1)
				(type default)
			)
			(layer "F.Fab")
		)
		(fp_line
			(start -0.12065 0.3048)
			(end -0.67945 0.3048)
			(stroke
				(width 0.1)
				(type default)
			)
			(layer "F.Fab")
		)
		(fp_line
			(start 0.120396 0.2794)
			(end -0.12065 0.2794)
			(stroke
				(width 0.1)
				(type default)
			)
			(layer "F.Fab")
		)
		(fp_line
			(start 0.120396 0.3048)
			(end 0.120396 0.2794)
			(stroke
				(width 0.1)
				(type default)
			)
			(layer "F.Fab")
		)
		(fp_line
			(start 0.12065 -0.3048)
			(end 0.67945 -0.3048)
			(stroke
				(width 0.1)
				(type default)
			)
			(layer "F.Fab")
		)
		(fp_line
			(start 0.12065 -0.2794)
			(end 0.12065 -0.3048)
			(stroke
				(width 0.1)
				(type default)
			)
			(layer "F.Fab")
		)
		(fp_line
			(start 0.67945 -0.3048)
			(end 0.67945 0.3048)
			(stroke
				(width 0.1)
				(type default)
			)
			(layer "F.Fab")
		)
		(fp_line
			(start 0.67945 0.3048)
			(end 0.120396 0.3048)
			(stroke
				(width 0.1)
				(type default)
			)
			(layer "F.Fab")
		)
		(pad "1" smd circle
			(at -0.40005 0)
			(size 0 0)
			(layers "F.Cu" "F.Mask" "F.Paste")
			(net "P3V3_AUX")
		)
		(pad "2" smd circle
			(at 0.40005 0)
			(size 0 0)
			(layers "F.Cu" "F.Mask" "F.Paste")
			(net "PCA9548_PCIE0_ADDR1")
		)
	)
	(footprint ""
		(layer "F.Cu")
		(at 450.049392 -47.506382 -90)
		(property "Reference" "PC2343"
			(at 0 0 270)
			(layer "F.SilkS")
			(hide yes)
			(effects
				(font
					(size 1.27 1.27)
				)
			)
		)
		(property "Value" ""
			(at 0 0 270)
			(layer "F.Fab")
			(effects
				(font
					(size 1.27 1.27)
				)
			)
		)
		(duplicate_pad_numbers_are_jumpers no)
		(fp_line
			(start -1.524 0.762)
			(end -1.524 -0.762)
			(stroke
				(width 0.1524)
				(type default)
			)
			(layer "F.SilkS")
		)
		(fp_line
			(start 1.524 0.762)
			(end -1.524 0.762)
			(stroke
				(width 0.1524)
				(type default)
			)
			(layer "F.SilkS")
		)
		(fp_line
			(start -1.524 -0.762)
			(end 1.524 -0.762)
			(stroke
				(width 0.1524)
				(type default)
			)
			(layer "F.SilkS")
		)
		(fp_line
			(start 1.524 -0.762)
			(end 1.524 0.762)
			(stroke
				(width 0.1524)
				(type default)
			)
			(layer "F.SilkS")
		)
		(fp_line
			(start -1.1049 0.724916)
			(end 1.1049 0.724916)
			(stroke
				(width 0.1)
				(type default)
			)
			(layer "F.Fab")
		)
		(fp_line
			(start 1.1049 0.724916)
			(end 1.1049 -0.724916)
			(stroke
				(width 0.1)
				(type default)
			)
			(layer "F.Fab")
		)
		(fp_line
			(start -1.1049 -0.724916)
			(end -1.1049 0.724916)
			(stroke
				(width 0.1)
				(type default)
			)
			(layer "F.Fab")
		)
		(fp_line
			(start 1.1049 -0.724916)
			(end -1.1049 -0.724916)
			(stroke
				(width 0.1)
				(type default)
			)
			(layer "F.Fab")
		)
		(pad "1" smd rect
			(at -0.889 0 90)
			(size 1.016 1.27)
			(layers "F.Cu" "F.Mask" "F.Paste")
			(net "SW_P3V3_AUX_FLT")
		)
		(pad "2" smd rect
			(at 0.889 0 90)
			(size 1.016 1.27)
			(layers "F.Cu" "F.Mask" "F.Paste")
			(net "GND")
		)
	)
	(footprint ""
		(layer "F.Cu")
		(at 440.40171 -13.627354 180)
		(property "Reference" "C27"
			(at 0 0 180)
			(layer "F.SilkS")
			(hide yes)
			(effects
				(font
					(size 1.27 1.27)
				)
			)
		)
		(property "Value" ""
			(at 0 0 180)
			(layer "F.Fab")
			(effects
				(font
					(size 1.27 1.27)
				)
			)
		)
		(duplicate_pad_numbers_are_jumpers no)
		(fp_line
			(start 0.7874 0.4064)
			(end -0.7874 0.4064)
			(stroke
				(width 0.1524)
				(type default)
			)
			(layer "F.SilkS")
		)
		(fp_line
			(start 0.7874 -0.4064)
			(end 0.7874 0.4064)
			(stroke
				(width 0.1524)
				(type default)
			)
			(layer "F.SilkS")
		)
		(fp_line
			(start -0.7874 0.4064)
			(end -0.7874 -0.4064)
			(stroke
				(width 0.1524)
				(type default)
			)
			(layer "F.SilkS")
		)
		(fp_line
			(start -0.7874 -0.4064)
			(end 0.7874 -0.4064)
			(stroke
				(width 0.1524)
				(type default)
			)
			(layer "F.SilkS")
		)
		(fp_line
			(start 0.67945 0.3048)
			(end 0.120396 0.3048)
			(stroke
				(width 0.1)
				(type default)
			)
			(layer "F.Fab")
		)
		(fp_line
			(start 0.67945 -0.3048)
			(end 0.67945 0.3048)
			(stroke
				(width 0.1)
				(type default)
			)
			(layer "F.Fab")
		)
		(fp_line
			(start 0.12065 -0.2794)
			(end 0.12065 -0.3048)
			(stroke
				(width 0.1)
				(type default)
			)
			(layer "F.Fab")
		)
		(fp_line
			(start 0.12065 -0.3048)
			(end 0.67945 -0.3048)
			(stroke
				(width 0.1)
				(type default)
			)
			(layer "F.Fab")
		)
		(fp_line
			(start 0.120396 0.3048)
			(end 0.120396 0.2794)
			(stroke
				(width 0.1)
				(type default)
			)
			(layer "F.Fab")
		)
		(fp_line
			(start 0.120396 0.2794)
			(end -0.12065 0.2794)
			(stroke
				(width 0.1)
				(type default)
			)
			(layer "F.Fab")
		)
		(fp_line
			(start -0.12065 0.3048)
			(end -0.67945 0.3048)
			(stroke
				(width 0.1)
				(type default)
			)
			(layer "F.Fab")
		)
		(fp_line
			(start -0.12065 0.2794)
			(end -0.12065 0.3048)
			(stroke
				(width 0.1)
				(type default)
			)
			(layer "F.Fab")
		)
		(fp_line
			(start -0.12065 -0.2794)
			(end 0.12065 -0.2794)
			(stroke
				(width 0.1)
				(type default)
			)
			(layer "F.Fab")
		)
		(fp_line
			(start -0.12065 -0.305054)
			(end -0.12065 -0.2794)
			(stroke
				(width 0.1)
				(type default)
			)
			(layer "F.Fab")
		)
		(fp_line
			(start -0.67945 0.3048)
			(end -0.67945 -0.305054)
			(stroke
				(width 0.1)
				(type default)
			)
			(layer "F.Fab")
		)
		(fp_line
			(start -0.67945 -0.305054)
			(end -0.12065 -0.305054)
			(stroke
				(width 0.1)
				(type default)
			)
			(layer "F.Fab")
		)
		(pad "1" smd circle
			(at -0.40005 0 180)
			(size 0 0)
			(layers "F.Cu" "F.Mask" "F.Paste")
			(net "P12V_OCP_SFF_R")
		)
		(pad "2" smd circle
			(at 0.40005 0 180)
			(size 0 0)
			(layers "F.Cu" "F.Mask" "F.Paste")
			(net "GND")
		)
	)
	(footprint ""
		(layer "F.Cu")
		(at 360.190542 -400.6088)
		(property "Reference" "R1391"
			(at 0 0 0)
			(layer "F.SilkS")
			(hide yes)
			(effects
				(font
					(size 1.27 1.27)
				)
			)
		)
		(property "Value" ""
			(at 0 0 0)
			(layer "F.Fab")
			(effects
				(font
					(size 1.27 1.27)
				)
			)
		)
		(duplicate_pad_numbers_are_jumpers no)
		(fp_line
			(start -0.32512 -0.175006)
			(end 0.32512 -0.175006)
			(stroke
				(width 0.1)
				(type default)
			)
			(layer "F.Fab")
		)
		(fp_line
			(start -0.32512 0.175006)
			(end -0.32512 -0.175006)
			(stroke
				(width 0.1)
				(type default)
			)
			(layer "F.Fab")
		)
		(fp_line
			(start 0.32512 -0.175006)
			(end 0.32512 0.175006)
			(stroke
				(width 0.1)
				(type default)
			)
			(layer "F.Fab")
		)
		(fp_line
			(start 0.32512 0.175006)
			(end -0.32512 0.175006)
			(stroke
				(width 0.1)
				(type default)
			)
			(layer "F.Fab")
		)
		(pad "1" smd rect
			(at -0.2667 0)
			(size 0.3048 0.381)
			(layers "F.Cu" "F.Mask" "F.Paste")
			(net "JTAG_TRST_RT_CPU0_P1_N")
		)
		(pad "2" smd rect
			(at 0.2667 0 180)
			(size 0.3048 0.381)
			(layers "F.Cu" "F.Mask" "F.Paste")
			(net "GND")
		)
	)
)
